# SCM (Grand Teton) — schematic netlist excerpt (pin names and nets, part order shuffled) for the footprints in the layout excerpt that follows; sources: Cadence DE-HDL packaged netlist, KiCad conversion of 12092022_DA0F0TMDCD0_F0T_Management_Board_D_brd_V3_OCP.brd

R46  Q_RES  33.2 1% CHIP  pkg 0402LF  page 10 : A = SMB_BMC_MM14_SDA ; B = SMB_BMC_MM14_R1_SDA
C189  Q_CAP  0.1UF 25V 10% X7R  pkg 0402  page 41 : A = VCCIO0 ; B = GND

(kicad_pcb
	(version 20260206)
	(generator "pcbnew")
	(generator_version "10.0")
	(general
		(thickness 1.6)
		(legacy_teardrops no)
	)
	(paper "A4")
	(title_block
		(title "12092022_DA0F0TMDCD0_F0T_Management_Board_D_brd_V3_OCP.brd")
		(comment 1 "Grand Teton / footprints 747-748 of 1440")
	)
	(layers
		(0 "F.Cu" signal "TOP")
		(4 "In1.Cu" signal "GND")
		(6 "In2.Cu" signal "IN1")
		(8 "In3.Cu" signal "GND1")
		(10 "In4.Cu" signal "IN2")
		(12 "In5.Cu" signal "VCC")
		(14 "In6.Cu" signal "VCC1")
		(16 "In7.Cu" signal "IN3")
		(18 "In8.Cu" signal "GND2")
		(20 "In9.Cu" signal "IN4")
		(22 "In10.Cu" signal "GND3")
		(2 "B.Cu" signal "BOTTOM")
		(9 "F.Adhes" user "F.Adhesive")
		(11 "B.Adhes" user "B.Adhesive")
		(13 "F.Paste" user "Package Geometry/Pastemask Top")
		(15 "B.Paste" user "Package Geometry/Pastemask Bottom")
		(5 "F.SilkS" user "Ref Des/Silkscreen Top")
		(7 "B.SilkS" user "Ref Des/Silkscreen Bottom")
		(1 "F.Mask" user "Board Geometry/Soldermask Top")
		(3 "B.Mask" user "Board Geometry/Soldermask Bottom")
		(17 "Dwgs.User" user "User.Drawings")
		(19 "Cmts.User" user "User.Comments")
		(21 "Eco1.User" user "User.Eco1")
		(23 "Eco2.User" user "User.Eco2")
		(25 "Edge.Cuts" user "Board Geometry/Outline")
		(27 "Margin" user)
		(31 "F.CrtYd" user "Package Geometry/Place Bound Top")
		(29 "B.CrtYd" user "Package Geometry/Place Bound Bottom")
		(35 "F.Fab" user "Ref Des/Assembly Top")
		(33 "B.Fab" user "Ref Des/Assembly Bottom")
	)
	(footprint ""
		(layer "B.Cu")
		(at 21.3106 -90.8558 90)
		(property "Reference" "C189"
			(at 0 0 90)
			(layer "B.SilkS")
			(hide yes)
			(effects
				(font
					(size 1.27 1.27)
				)
				(justify mirror)
			)
		)
		(property "Value" ""
			(at 0 0 90)
			(layer "B.Fab")
			(effects
				(font
					(size 1.27 1.27)
				)
				(justify mirror)
			)
		)
		(duplicate_pad_numbers_are_jumpers no)
		(fp_line
			(start 0.69215 -0.2921)
			(end -0.69215 -0.2921)
			(stroke
				(width 0.1524)
				(type default)
			)
			(layer "B.SilkS")
		)
		(fp_line
			(start -0.69215 -0.2921)
			(end -0.69215 0.2921)
			(stroke
				(width 0.1524)
				(type default)
			)
			(layer "B.SilkS")
		)
		(fp_line
			(start 0.69215 0.2921)
			(end 0.69215 -0.2921)
			(stroke
				(width 0.1524)
				(type default)
			)
			(layer "B.SilkS")
		)
		(fp_line
			(start -0.69215 0.2921)
			(end 0.69215 0.2921)
			(stroke
				(width 0.1524)
				(type default)
			)
			(layer "B.SilkS")
		)
		(fp_line
			(start 0.51435 -0.2794)
			(end -0.51435 -0.2794)
			(stroke
				(width 0.1)
				(type default)
			)
			(layer "B.Fab")
		)
		(fp_line
			(start -0.51435 -0.2794)
			(end -0.51435 0.2794)
			(stroke
				(width 0.1)
				(type default)
			)
			(layer "B.Fab")
		)
		(fp_line
			(start 0.51435 0.2794)
			(end 0.51435 -0.2794)
			(stroke
				(width 0.1)
				(type default)
			)
			(layer "B.Fab")
		)
		(fp_line
			(start -0.51435 0.2794)
			(end 0.51435 0.2794)
			(stroke
				(width 0.1)
				(type default)
			)
			(layer "B.Fab")
		)
		(pad "1" smd circle
			(at 0.40005 0 270)
			(size 0 0)
			(layers "B.Cu" "B.Mask" "B.Paste")
			(net "VCCIO0")
		)
		(pad "2" smd circle
			(at -0.40005 0 270)
			(size 0 0)
			(layers "B.Cu" "B.Mask" "B.Paste")
			(net "GND")
		)
		(zone
			(layer "B.Cu")
			(hatch none 0.5)
			(connect_pads
				(clearance 0)
			)
			(min_thickness 0.25)
			(keepout
				(tracks not_allowed)
				(vias allowed)
				(pads allowed)
				(copperpour not_allowed)
				(footprints allowed)
			)
			(placement
				(enabled no)
				(sheetname "")
			)
			(fill
				(thermal_gap 0.5)
				(thermal_bridge_width 0.5)
				(island_removal_mode 0)
			)
			(polygon
				(pts
					(xy 21.39823 -91.0463) (xy 21.456396 -90.95486) (xy 21.456396 -90.75547) (xy 21.39823 -90.6653)
					(xy 21.22297 -90.6653) (xy 21.16455 -90.75547) (xy 21.16455 -90.95486) (xy 21.222716 -91.0463)
				)
			)
		)
	)
	(footprint ""
		(layer "B.Cu")
		(at 66.3956 -106.4387 -90)
		(property "Reference" "R46"
			(at 0 0 90)
			(layer "B.SilkS")
			(hide yes)
			(effects
				(font
					(size 1.27 1.27)
				)
				(justify mirror)
			)
		)
		(property "Value" ""
			(at 0 0 90)
			(layer "B.Fab")
			(effects
				(font
					(size 1.27 1.27)
				)
				(justify mirror)
			)
		)
		(duplicate_pad_numbers_are_jumpers no)
		(fp_line
			(start -0.7874 0.4064)
			(end 0.7874 0.4064)
			(stroke
				(width 0.1524)
				(type default)
			)
			(layer "B.SilkS")
		)
		(fp_line
			(start 0.7874 0.4064)
			(end 0.7874 -0.4064)
			(stroke
				(width 0.1524)
				(type default)
			)
			(layer "B.SilkS")
		)
		(fp_line
			(start -0.7874 -0.4064)
			(end -0.7874 0.4064)
			(stroke
				(width 0.1524)
				(type default)
			)
			(layer "B.SilkS")
		)
		(fp_line
			(start 0.7874 -0.4064)
			(end -0.7874 -0.4064)
			(stroke
				(width 0.1524)
				(type default)
			)
			(layer "B.SilkS")
		)
		(fp_line
			(start -0.67945 0.3048)
			(end -0.120396 0.3048)
			(stroke
				(width 0.1)
				(type default)
			)
			(layer "B.Fab")
		)
		(fp_line
			(start -0.120396 0.3048)
			(end -0.120396 0.2794)
			(stroke
				(width 0.1)
				(type default)
			)
			(layer "B.Fab")
		)
		(fp_line
			(start 0.12065 0.3048)
			(end 0.67945 0.3048)
			(stroke
				(width 0.1)
				(type default)
			)
			(layer "B.Fab")
		)
		(fp_line
			(start 0.67945 0.3048)
			(end 0.67945 -0.305054)
			(stroke
				(width 0.1)
				(type default)
			)
			(layer "B.Fab")
		)
		(fp_line
			(start -0.120396 0.2794)
			(end 0.12065 0.2794)
			(stroke
				(width 0.1)
				(type default)
			)
			(layer "B.Fab")
		)
		(fp_line
			(start 0.12065 0.2794)
			(end 0.12065 0.3048)
			(stroke
				(width 0.1)
				(type default)
			)
			(layer "B.Fab")
		)
		(fp_line
			(start -0.12065 -0.2794)
			(end -0.12065 -0.3048)
			(stroke
				(width 0.1)
				(type default)
			)
			(layer "B.Fab")
		)
		(fp_line
			(start 0.12065 -0.2794)
			(end -0.12065 -0.2794)
			(stroke
				(width 0.1)
				(type default)
			)
			(layer "B.Fab")
		)
		(fp_line
			(start -0.67945 -0.3048)
			(end -0.67945 0.3048)
			(stroke
				(width 0.1)
				(type default)
			)
			(layer "B.Fab")
		)
		(fp_line
			(start -0.12065 -0.3048)
			(end -0.67945 -0.3048)
			(stroke
				(width 0.1)
				(type default)
			)
			(layer "B.Fab")
		)
		(fp_line
			(start 0.12065 -0.305054)
			(end 0.12065 -0.2794)
			(stroke
				(width 0.1)
				(type default)
			)
			(layer "B.Fab")
		)
		(fp_line
			(start 0.67945 -0.305054)
			(end 0.12065 -0.305054)
			(stroke
				(width 0.1)
				(type default)
			)
			(layer "B.Fab")
		)
		(pad "1" smd circle
			(at 0.40005 0 90)
			(size 0 0)
			(layers "B.Cu" "B.Mask" "B.Paste")
			(net "SMB_BMC_MM14_SDA")
		)
		(pad "2" smd circle
			(at -0.40005 0 90)
			(size 0 0)
			(layers "B.Cu" "B.Mask" "B.Paste")
			(net "SMB_BMC_MM14_R1_SDA")
		)
	)
)
